# S9S_MB_2U (Grand Teton) — schematic netlist excerpt (pin names and nets, part order shuffled) for the footprints in the layout excerpt that follows; sources: Cadence DE-HDL packaged netlist, KiCad conversion of 03242023_DA0F0TMBIJ0_F0T_Motherboard_J_brd_V01_OCP.brd

C1307  Q_CAP  1000PF 50V 5% EMPTY  pkg 0402  page 282 : A = FM_PVNN_MAIN_CPU0_EN ; B = GND
PR2514  Q_RES  10 1% EMPTY  pkg 0402LF  page 304 : A = P12V_HSC_ADC_P ; B = P12V_HSC_SENSE1_P
PC566_P1_2  Q_CAP  22UF 16V 20% X6S  pkg C0805  page 285 : A = SW_P12V_PVCCIN_CPU1_FLT ; B = GND

(kicad_pcb
	(version 20260206)
	(generator "pcbnew")
	(generator_version "10.0")
	(general
		(thickness 1.6)
		(legacy_teardrops no)
	)
	(paper "A4")
	(title_block
		(title "03242023_DA0F0TMBIJ0_F0T_Motherboard_J_brd_V01_OCP.brd")
		(comment 1 "Grand Teton / footprints 4920-4922 of 6105")
	)
	(layers
		(0 "F.Cu" signal "TOP")
		(4 "In1.Cu" signal "GND")
		(6 "In2.Cu" signal "IN1")
		(8 "In3.Cu" signal "GND1")
		(10 "In4.Cu" signal "IN2")
		(12 "In5.Cu" signal "GND2")
		(14 "In6.Cu" signal "IN3")
		(16 "In7.Cu" signal "GND3")
		(18 "In8.Cu" signal "VCC")
		(20 "In9.Cu" signal "VCC1")
		(22 "In10.Cu" signal "GND4")
		(24 "In11.Cu" signal "IN4")
		(26 "In12.Cu" signal "GND5")
		(28 "In13.Cu" signal "IN5")
		(30 "In14.Cu" signal "GND6")
		(32 "In15.Cu" signal "IN6")
		(34 "In16.Cu" signal "GND7")
		(2 "B.Cu" signal "BOTTOM")
		(9 "F.Adhes" user "F.Adhesive")
		(11 "B.Adhes" user "B.Adhesive")
		(13 "F.Paste" user "Package Geometry/Pastemask Top")
		(15 "B.Paste" user "Package Geometry/Pastemask Bottom")
		(5 "F.SilkS" user "Ref Des/Silkscreen Top")
		(7 "B.SilkS" user "Ref Des/Silkscreen Bottom")
		(1 "F.Mask" user "Board Geometry/Soldermask Top")
		(3 "B.Mask" user "Board Geometry/Soldermask Bottom")
		(17 "Dwgs.User" user "User.Drawings")
		(19 "Cmts.User" user "User.Comments")
		(21 "Eco1.User" user "User.Eco1")
		(23 "Eco2.User" user "User.Eco2")
		(25 "Edge.Cuts" user "Board Geometry/Outline")
		(27 "Margin" user)
		(31 "F.CrtYd" user "Package Geometry/Place Bound Top")
		(29 "B.CrtYd" user "Package Geometry/Place Bound Bottom")
		(35 "F.Fab" user "Ref Des/Assembly Top")
		(33 "B.Fab" user "Ref Des/Assembly Bottom")
	)
	(footprint ""
		(layer "B.Cu")
		(at 288.464498 -403.031452 90)
		(property "Reference" "PR2514"
			(at 0 0 90)
			(layer "B.SilkS")
			(hide yes)
			(effects
				(font
					(size 1.27 1.27)
				)
				(justify mirror)
			)
		)
		(property "Value" ""
			(at 0 0 90)
			(layer "B.Fab")
			(effects
				(font
					(size 1.27 1.27)
				)
				(justify mirror)
			)
		)
		(duplicate_pad_numbers_are_jumpers no)
		(fp_line
			(start 0.7874 -0.4064)
			(end -0.7874 -0.4064)
			(stroke
				(width 0.1524)
				(type default)
			)
			(layer "B.SilkS")
		)
		(fp_line
			(start -0.7874 -0.4064)
			(end -0.7874 0.4064)
			(stroke
				(width 0.1524)
				(type default)
			)
			(layer "B.SilkS")
		)
		(fp_line
			(start 0.7874 0.4064)
			(end 0.7874 -0.4064)
			(stroke
				(width 0.1524)
				(type default)
			)
			(layer "B.SilkS")
		)
		(fp_line
			(start -0.7874 0.4064)
			(end 0.7874 0.4064)
			(stroke
				(width 0.1524)
				(type default)
			)
			(layer "B.SilkS")
		)
		(fp_line
			(start 0.67945 -0.305054)
			(end 0.12065 -0.305054)
			(stroke
				(width 0.1)
				(type default)
			)
			(layer "B.Fab")
		)
		(fp_line
			(start 0.12065 -0.305054)
			(end 0.12065 -0.2794)
			(stroke
				(width 0.1)
				(type default)
			)
			(layer "B.Fab")
		)
		(fp_line
			(start -0.12065 -0.3048)
			(end -0.67945 -0.3048)
			(stroke
				(width 0.1)
				(type default)
			)
			(layer "B.Fab")
		)
		(fp_line
			(start -0.67945 -0.3048)
			(end -0.67945 0.3048)
			(stroke
				(width 0.1)
				(type default)
			)
			(layer "B.Fab")
		)
		(fp_line
			(start 0.12065 -0.2794)
			(end -0.12065 -0.2794)
			(stroke
				(width 0.1)
				(type default)
			)
			(layer "B.Fab")
		)
		(fp_line
			(start -0.12065 -0.2794)
			(end -0.12065 -0.3048)
			(stroke
				(width 0.1)
				(type default)
			)
			(layer "B.Fab")
		)
		(fp_line
			(start 0.12065 0.2794)
			(end 0.12065 0.3048)
			(stroke
				(width 0.1)
				(type default)
			)
			(layer "B.Fab")
		)
		(fp_line
			(start -0.120396 0.2794)
			(end 0.12065 0.2794)
			(stroke
				(width 0.1)
				(type default)
			)
			(layer "B.Fab")
		)
		(fp_line
			(start 0.67945 0.3048)
			(end 0.67945 -0.305054)
			(stroke
				(width 0.1)
				(type default)
			)
			(layer "B.Fab")
		)
		(fp_line
			(start 0.12065 0.3048)
			(end 0.67945 0.3048)
			(stroke
				(width 0.1)
				(type default)
			)
			(layer "B.Fab")
		)
		(fp_line
			(start -0.120396 0.3048)
			(end -0.120396 0.2794)
			(stroke
				(width 0.1)
				(type default)
			)
			(layer "B.Fab")
		)
		(fp_line
			(start -0.67945 0.3048)
			(end -0.120396 0.3048)
			(stroke
				(width 0.1)
				(type default)
			)
			(layer "B.Fab")
		)
		(pad "1" smd circle
			(at 0.40005 0 270)
			(size 0 0)
			(layers "B.Cu" "B.Mask" "B.Paste")
			(net "P12V_HSC_ADC_P")
		)
		(pad "2" smd circle
			(at -0.40005 0 270)
			(size 0 0)
			(layers "B.Cu" "B.Mask" "B.Paste")
			(net "P12V_HSC_SENSE1_P")
		)
	)
	(footprint ""
		(layer "B.Cu")
		(at 433.328318 -177.15611 90)
		(property "Reference" "C1307"
			(at 0 0 90)
			(layer "B.SilkS")
			(hide yes)
			(effects
				(font
					(size 1.27 1.27)
				)
				(justify mirror)
			)
		)
		(property "Value" ""
			(at 0 0 90)
			(layer "B.Fab")
			(effects
				(font
					(size 1.27 1.27)
				)
				(justify mirror)
			)
		)
		(duplicate_pad_numbers_are_jumpers no)
		(fp_line
			(start 0.7874 -0.4064)
			(end -0.7874 -0.4064)
			(stroke
				(width 0.1524)
				(type default)
			)
			(layer "B.SilkS")
		)
		(fp_line
			(start -0.7874 -0.4064)
			(end -0.7874 0.4064)
			(stroke
				(width 0.1524)
				(type default)
			)
			(layer "B.SilkS")
		)
		(fp_line
			(start 0.7874 0.4064)
			(end 0.7874 -0.4064)
			(stroke
				(width 0.1524)
				(type default)
			)
			(layer "B.SilkS")
		)
		(fp_line
			(start -0.7874 0.4064)
			(end 0.7874 0.4064)
			(stroke
				(width 0.1524)
				(type default)
			)
			(layer "B.SilkS")
		)
		(fp_line
			(start 0.67945 -0.305054)
			(end 0.12065 -0.305054)
			(stroke
				(width 0.1)
				(type default)
			)
			(layer "B.Fab")
		)
		(fp_line
			(start 0.12065 -0.305054)
			(end 0.12065 -0.2794)
			(stroke
				(width 0.1)
				(type default)
			)
			(layer "B.Fab")
		)
		(fp_line
			(start -0.12065 -0.3048)
			(end -0.67945 -0.3048)
			(stroke
				(width 0.1)
				(type default)
			)
			(layer "B.Fab")
		)
		(fp_line
			(start -0.67945 -0.3048)
			(end -0.67945 0.3048)
			(stroke
				(width 0.1)
				(type default)
			)
			(layer "B.Fab")
		)
		(fp_line
			(start 0.12065 -0.2794)
			(end -0.12065 -0.2794)
			(stroke
				(width 0.1)
				(type default)
			)
			(layer "B.Fab")
		)
		(fp_line
			(start -0.12065 -0.2794)
			(end -0.12065 -0.3048)
			(stroke
				(width 0.1)
				(type default)
			)
			(layer "B.Fab")
		)
		(fp_line
			(start 0.12065 0.2794)
			(end 0.12065 0.3048)
			(stroke
				(width 0.1)
				(type default)
			)
			(layer "B.Fab")
		)
		(fp_line
			(start -0.120396 0.2794)
			(end 0.12065 0.2794)
			(stroke
				(width 0.1)
				(type default)
			)
			(layer "B.Fab")
		)
		(fp_line
			(start 0.67945 0.3048)
			(end 0.67945 -0.305054)
			(stroke
				(width 0.1)
				(type default)
			)
			(layer "B.Fab")
		)
		(fp_line
			(start 0.12065 0.3048)
			(end 0.67945 0.3048)
			(stroke
				(width 0.1)
				(type default)
			)
			(layer "B.Fab")
		)
		(fp_line
			(start -0.120396 0.3048)
			(end -0.120396 0.2794)
			(stroke
				(width 0.1)
				(type default)
			)
			(layer "B.Fab")
		)
		(fp_line
			(start -0.67945 0.3048)
			(end -0.120396 0.3048)
			(stroke
				(width 0.1)
				(type default)
			)
			(layer "B.Fab")
		)
		(pad "1" smd circle
			(at 0.40005 0 270)
			(size 0 0)
			(layers "B.Cu" "B.Mask" "B.Paste")
			(net "FM_PVNN_MAIN_CPU0_EN")
		)
		(pad "2" smd circle
			(at -0.40005 0 270)
			(size 0 0)
			(layers "B.Cu" "B.Mask" "B.Paste")
			(net "GND")
		)
	)
	(footprint ""
		(layer "B.Cu")
		(at 106.27995 -333.639922 90)
		(property "Reference" "PC566_P1_2"
			(at 0 0 90)
			(layer "B.SilkS")
			(hide yes)
			(effects
				(font
					(size 1.27 1.27)
				)
				(justify mirror)
			)
		)
		(property "Value" ""
			(at 0 0 90)
			(layer "B.Fab")
			(effects
				(font
					(size 1.27 1.27)
				)
				(justify mirror)
			)
		)
		(duplicate_pad_numbers_are_jumpers no)
		(fp_line
			(start 1.524 -0.762)
			(end -1.524 -0.762)
			(stroke
				(width 0.1524)
				(type default)
			)
			(layer "B.SilkS")
		)
		(fp_line
			(start -1.524 -0.762)
			(end -1.524 0.762)
			(stroke
				(width 0.1524)
				(type default)
			)
			(layer "B.SilkS")
		)
		(fp_line
			(start 1.524 0.762)
			(end 1.524 -0.762)
			(stroke
				(width 0.1524)
				(type default)
			)
			(layer "B.SilkS")
		)
		(fp_line
			(start -1.524 0.762)
			(end 1.524 0.762)
			(stroke
				(width 0.1524)
				(type default)
			)
			(layer "B.SilkS")
		)
		(fp_line
			(start 1.1049 -0.724916)
			(end 1.1049 0.724916)
			(stroke
				(width 0.1)
				(type default)
			)
			(layer "B.Fab")
		)
		(fp_line
			(start -1.1049 -0.724916)
			(end 1.1049 -0.724916)
			(stroke
				(width 0.1)
				(type default)
			)
			(layer "B.Fab")
		)
		(fp_line
			(start 1.1049 0.724916)
			(end -1.1049 0.724916)
			(stroke
				(width 0.1)
				(type default)
			)
			(layer "B.Fab")
		)
		(fp_line
			(start -1.1049 0.724916)
			(end -1.1049 -0.724916)
			(stroke
				(width 0.1)
				(type default)
			)
			(layer "B.Fab")
		)
		(pad "1" smd rect
			(at 0.889 0 90)
			(size 1.016 1.27)
			(layers "B.Cu" "B.Mask" "B.Paste")
			(net "SW_P12V_PVCCIN_CPU1_FLT")
		)
		(pad "2" smd rect
			(at -0.889 0 90)
			(size 1.016 1.27)
			(layers "B.Cu" "B.Mask" "B.Paste")
			(net "GND")
		)
	)
)
